(kicad_pcb
	(version 20241229)
	(generator "pcbnew")
	(generator_version "9.0")
	(general
		(thickness 1.63)
		(legacy_teardrops no)
	)
	(paper "A4")
	(title_block
		(title "CM4 Baseboard")
		(date "2026-01-05")
		(rev "1.1.1")
		(company "Antmicro Ltd")
		(comment 1 "www.antmicro.com")
		(comment 9 "footprints 156-159 of 506")
	)
	(layers
		(0 "F.Cu" signal)
		(4 "In1.Cu" power)
		(6 "In2.Cu" power)
		(8 "In3.Cu" signal)
		(10 "In4.Cu" signal)
		(2 "B.Cu" signal)
		(9 "F.Adhes" user "F.Adhesive")
		(11 "B.Adhes" user "B.Adhesive")
		(13 "F.Paste" user)
		(15 "B.Paste" user)
		(5 "F.SilkS" user "F.Silkscreen")
		(7 "B.SilkS" user "B.Silkscreen")
		(1 "F.Mask" user)
		(3 "B.Mask" user)
		(17 "Dwgs.User" user "User.Drawings")
		(19 "Cmts.User" user "User.Comments")
		(21 "Eco1.User" user "User.Eco1")
		(23 "Eco2.User" user "User.Eco2")
		(25 "Edge.Cuts" user)
		(27 "Margin" user)
		(31 "F.CrtYd" user "F.Courtyard")
		(29 "B.CrtYd" user "B.Courtyard")
		(35 "F.Fab" user)
		(33 "B.Fab" user)
	)
	(footprint "antmicro-footprints:C_0402_1005Metric"
		(layer "F.Cu")
		(at 66.917962 170.4165)
		(descr "Capacitor SMD 0402")
		(tags "capacitor SMD 0402")
		(property "Reference" "C803"
			(at -9.611139 3.137927 0)
			(layer "F.SilkS")
			(effects
				(font
					(size 0.7 0.7)
					(thickness 0.15)
				)
				(justify left bottom)
			)
		)
		(property "Value" "C_4u7_0402"
			(at -1.022927 2.155213 0)
			(layer "F.Fab")
			(effects
				(font
					(size 0.7 0.7)
					(thickness 0.15)
				)
				(justify left bottom)
			)
		)
		(property "Datasheet" "https://www.murata.com/products/productdetail?partno=GRM155R61A475MEAA%23"
			(at 0 0 0)
			(layer "F.Fab")
			(hide yes)
			(effects
				(font
					(size 1.27 1.27)
					(thickness 0.15)
				)
			)
		)
		(property "MPN" "GRM155R61A475MEAAD"
			(at 0 0 0)
			(unlocked yes)
			(layer "F.Fab")
			(hide yes)
			(effects
				(font
					(size 1 1)
					(thickness 0.15)
				)
			)
		)
		(property "Manufacturer" "Murata"
			(at 0 0 0)
			(unlocked yes)
			(layer "F.Fab")
			(hide yes)
			(effects
				(font
					(size 1 1)
					(thickness 0.15)
				)
			)
		)
		(property "License" "Apache-2.0"
			(at 0 0 0)
			(unlocked yes)
			(layer "F.Fab")
			(hide yes)
			(effects
				(font
					(size 1 1)
					(thickness 0.15)
				)
			)
		)
		(property "Author" "Antmicro"
			(at 0 0 0)
			(unlocked yes)
			(layer "F.Fab")
			(hide yes)
			(effects
				(font
					(size 1 1)
					(thickness 0.15)
				)
			)
		)
		(property "Val" "4u7"
			(at 0 0 0)
			(unlocked yes)
			(layer "F.Fab")
			(hide yes)
			(effects
				(font
					(size 1 1)
					(thickness 0.15)
				)
			)
		)
		(property "Voltage" ""
			(at 0 0 0)
			(unlocked yes)
			(layer "F.Fab")
			(hide yes)
			(effects
				(font
					(size 1 1)
					(thickness 0.15)
				)
			)
		)
		(property "Dielectric" ""
			(at 0 0 0)
			(unlocked yes)
			(layer "F.Fab")
			(hide yes)
			(effects
				(font
					(size 1 1)
					(thickness 0.15)
				)
			)
		)
		(sheetname "/Peripherals/")
		(sheetfile "peripherals.kicad_sch")
		(attr smd)
		(fp_rect
			(start -0.925 -0.47)
			(end 0.925 0.47)
			(stroke
				(width 0.05)
				(type default)
			)
			(fill no)
			(layer "F.CrtYd")
		)
		(fp_line
			(start -0.494 -0.25)
			(end 0.504 -0.25)
			(stroke
				(width 0.15)
				(type solid)
			)
			(layer "F.Fab")
		)
		(fp_line
			(start -0.494 0.248)
			(end -0.494 -0.25)
			(stroke
				(width 0.15)
				(type solid)
			)
			(layer "F.Fab")
		)
		(fp_line
			(start 0.504 -0.25)
			(end 0.504 0.248)
			(stroke
				(width 0.15)
				(type solid)
			)
			(layer "F.Fab")
		)
		(fp_line
			(start 0.504 0.248)
			(end -0.494 0.248)
			(stroke
				(width 0.15)
				(type solid)
			)
			(layer "F.Fab")
		)
		(fp_text user "License: Apache-2.0"
			(at -0.939 5.799 0)
			(layer "F.Fab")
			(effects
				(font
					(size 0.7 0.7)
					(thickness 0.15)
				)
				(justify left bottom)
			)
		)
		(fp_text user "Author: Antmicro"
			(at -0.939 3.399 0)
			(layer "F.Fab")
			(effects
				(font
					(size 0.7 0.7)
					(thickness 0.15)
				)
				(justify left bottom)
			)
		)
		(fp_text user "${REFERENCE}"
			(at -0.939 4.599 0)
			(layer "F.Fab")
			(effects
				(font
					(size 0.7 0.7)
					(thickness 0.15)
				)
				(justify left bottom)
			)
		)
		(pad "1" smd roundrect
			(at -0.48 0)
			(size 0.59 0.64)
			(layers "F.Cu" "F.Mask" "F.Paste")
			(roundrect_rratio 0.25)
			(net 3 "GND")
			(pintype "passive")
		)
		(pad "2" smd roundrect
			(at 0.48 0)
			(size 0.59 0.64)
			(layers "F.Cu" "F.Mask" "F.Paste")
			(roundrect_rratio 0.25)
			(net 501 "Net-(U801-V_{DD(UP)})")
			(pintype "passive")
		)
	)
	(footprint "antmicro-footprints:C_0402_1005Metric"
		(layer "F.Cu")
		(at 139.517962 159.4915 90)
		(descr "Capacitor SMD 0402")
		(tags "capacitor SMD 0402")
		(property "Reference" "C601"
			(at -1.3585 1.232038 90)
			(layer "F.SilkS")
			(effects
				(font
					(size 0.7 0.7)
					(thickness 0.15)
				)
				(justify left bottom)
			)
		)
		(property "Value" "C_100n_0402"
			(at -1.022927 2.155213 90)
			(layer "F.Fab")
			(effects
				(font
					(size 0.7 0.7)
					(thickness 0.15)
				)
				(justify left bottom)
			)
		)
		(property "Datasheet" "https://www.murata.com/products/productdetail?partno=GRM155R61H104KE14%23"
			(at 0 0 90)
			(layer "F.Fab")
			(hide yes)
			(effects
				(font
					(size 1.27 1.27)
					(thickness 0.15)
				)
			)
		)
		(property "Manufacturer" "Murata"
			(at 0 0 90)
			(unlocked yes)
			(layer "F.Fab")
			(hide yes)
			(effects
				(font
					(size 1 1)
					(thickness 0.15)
				)
			)
		)
		(property "MPN" "GRM155R61H104KE14D"
			(at 0 0 90)
			(unlocked yes)
			(layer "F.Fab")
			(hide yes)
			(effects
				(font
					(size 1 1)
					(thickness 0.15)
				)
			)
		)
		(property "Val" "100n"
			(at 0 0 90)
			(unlocked yes)
			(layer "F.Fab")
			(hide yes)
			(effects
				(font
					(size 1 1)
					(thickness 0.15)
				)
			)
		)
		(property "License" "Apache-2.0"
			(at 0 0 90)
			(unlocked yes)
			(layer "F.Fab")
			(hide yes)
			(effects
				(font
					(size 1 1)
					(thickness 0.15)
				)
			)
		)
		(property "Author" "Antmicro"
			(at 0 0 90)
			(unlocked yes)
			(layer "F.Fab")
			(hide yes)
			(effects
				(font
					(size 1 1)
					(thickness 0.15)
				)
			)
		)
		(property "Voltage" "50V"
			(at 0 0 90)
			(unlocked yes)
			(layer "F.Fab")
			(hide yes)
			(effects
				(font
					(size 1 1)
					(thickness 0.15)
				)
			)
		)
		(property "Dielectric" "X5R"
			(at 0 0 90)
			(unlocked yes)
			(layer "F.Fab")
			(hide yes)
			(effects
				(font
					(size 1 1)
					(thickness 0.15)
				)
			)
		)
		(sheetname "/CSI/")
		(sheetfile "csi.kicad_sch")
		(attr smd)
		(fp_rect
			(start -0.925 -0.47)
			(end 0.925 0.47)
			(stroke
				(width 0.05)
				(type default)
			)
			(fill no)
			(layer "F.CrtYd")
		)
		(fp_line
			(start 0.504 -0.25)
			(end 0.504 0.248)
			(stroke
				(width 0.15)
				(type solid)
			)
			(layer "F.Fab")
		)
		(fp_line
			(start -0.494 -0.25)
			(end 0.504 -0.25)
			(stroke
				(width 0.15)
				(type solid)
			)
			(layer "F.Fab")
		)
		(fp_line
			(start 0.504 0.248)
			(end -0.494 0.248)
			(stroke
				(width 0.15)
				(type solid)
			)
			(layer "F.Fab")
		)
		(fp_line
			(start -0.494 0.248)
			(end -0.494 -0.25)
			(stroke
				(width 0.15)
				(type solid)
			)
			(layer "F.Fab")
		)
		(fp_text user "Author: Antmicro"
			(at -0.939 3.399 90)
			(layer "F.Fab")
			(effects
				(font
					(size 0.7 0.7)
					(thickness 0.15)
				)
				(justify left bottom)
			)
		)
		(fp_text user "${REFERENCE}"
			(at -0.939 4.599 90)
			(layer "F.Fab")
			(effects
				(font
					(size 0.7 0.7)
					(thickness 0.15)
				)
				(justify left bottom)
			)
		)
		(fp_text user "License: Apache-2.0"
			(at -0.939 5.799 90)
			(layer "F.Fab")
			(effects
				(font
					(size 0.7 0.7)
					(thickness 0.15)
				)
				(justify left bottom)
			)
		)
		(pad "1" smd roundrect
			(at -0.48 0 90)
			(size 0.59 0.64)
			(layers "F.Cu" "F.Mask" "F.Paste")
			(roundrect_rratio 0.25)
			(net 10 "+5V")
			(pintype "passive")
		)
		(pad "2" smd roundrect
			(at 0.48 0 90)
			(size 0.59 0.64)
			(layers "F.Cu" "F.Mask" "F.Paste")
			(roundrect_rratio 0.25)
			(net 3 "GND")
			(pintype "passive")
		)
	)
	(footprint "antmicro-footprints:SOD-123FL"
		(layer "F.Cu")
		(at 75.767962 121.2165 180)
		(property "Reference" "D904"
			(at 2.107962 1.6565 90)
			(layer "F.SilkS")
			(effects
				(font
					(size 0.7 0.7)
					(thickness 0.15)
				)
				(justify right bottom)
			)
		)
		(property "Value" "SMF4L15A"
			(at 0 1.967 0)
			(layer "F.Fab")
			(effects
				(font
					(size 0.7 0.7)
					(thickness 0.15)
				)
				(justify right bottom)
			)
		)
		(property "Datasheet" "https://www.littelfuse.com/media?resourcetype=datasheets&itemid=d2ba8fab-1de3-4176-8530-f36ecb0b8799&filename=smf4l"
			(at 0 0 180)
			(layer "F.Fab")
			(hide yes)
			(effects
				(font
					(size 1.27 1.27)
					(thickness 0.15)
				)
			)
		)
		(property "MPN" "SMF4L15A"
			(at 0 0 180)
			(unlocked yes)
			(layer "F.Fab")
			(hide yes)
			(effects
				(font
					(size 1 1)
					(thickness 0.15)
				)
			)
		)
		(property "Manufacturer" "Littelfuse"
			(at 0 0 180)
			(unlocked yes)
			(layer "F.Fab")
			(hide yes)
			(effects
				(font
					(size 1 1)
					(thickness 0.15)
				)
			)
		)
		(property "Author" "Antmicro"
			(at 0 0 180)
			(unlocked yes)
			(layer "F.Fab")
			(hide yes)
			(effects
				(font
					(size 1 1)
					(thickness 0.15)
				)
			)
		)
		(property "License" "Apache-2.0"
			(at 0 0 180)
			(unlocked yes)
			(layer "F.Fab")
			(hide yes)
			(effects
				(font
					(size 1 1)
					(thickness 0.15)
				)
			)
		)
		(sheetname "/USB/")
		(sheetfile "usb.kicad_sch")
		(attr smd)
		(fp_line
			(start 0 -1.1)
			(end -2.3 -1.1)
			(stroke
				(width 0.15)
				(type solid)
			)
			(layer "F.SilkS")
		)
		(fp_line
			(start -2.3 1.1)
			(end 0 1.1)
			(stroke
				(width 0.15)
				(type solid)
			)
			(layer "F.SilkS")
		)
		(fp_line
			(start -2.3 -1.1)
			(end -2.3 1.1)
			(stroke
				(width 0.15)
				(type solid)
			)
			(layer "F.SilkS")
		)
		(fp_rect
			(start -2.35 -1.125)
			(end 2.35 1.125)
			(stroke
				(width 0.05)
				(type solid)
			)
			(fill no)
			(layer "F.CrtYd")
		)
		(fp_rect
			(start -0.775 -0.875)
			(end -0.525 0.875)
			(stroke
				(width 0.15)
				(type solid)
			)
			(fill yes)
			(layer "F.Fab")
		)
		(fp_rect
			(start -1.825 -0.875)
			(end 1.824 0.873)
			(stroke
				(width 0.15)
				(type solid)
			)
			(fill no)
			(layer "F.Fab")
		)
		(fp_text user "${REFERENCE}"
			(at -2.406 3.967 180)
			(layer "F.Fab")
			(effects
				(font
					(size 0.7 0.7)
					(thickness 0.15)
				)
				(justify left bottom)
			)
		)
		(fp_text user "Author: Antmicro"
			(at -2.406 5.168 180)
			(layer "F.Fab")
			(effects
				(font
					(size 0.7 0.7)
					(thickness 0.15)
				)
				(justify left bottom)
			)
		)
		(fp_text user "License: Apache-2.0"
			(at -2.406 6.368 180)
			(layer "F.Fab")
			(effects
				(font
					(size 0.7 0.7)
					(thickness 0.15)
				)
				(justify left bottom)
			)
		)
		(pad "1" smd roundrect
			(at -1.43 0 180)
			(size 1.34 1.8)
			(layers "F.Cu" "F.Mask" "F.Paste")
			(roundrect_rratio 0.14)
			(net 26 "/USB/USBD_VBUS")
			(pinfunction "C")
			(pintype "passive")
		)
		(pad "2" smd roundrect
			(at 1.429 0 180)
			(size 1.34 1.8)
			(layers "F.Cu" "F.Mask" "F.Paste")
			(roundrect_rratio 0.14)
			(net 3 "GND")
			(pinfunction "A")
			(pintype "passive")
		)
	)
	(footprint "antmicro-footprints:SOT-23-3"
		(layer "F.Cu")
		(at 101.667962 129.7165 90)
		(property "Reference" "Q903"
			(at -1.83 -1.62 90)
			(layer "F.SilkS")
			(effects
				(font
					(size 0.7 0.7)
					(thickness 0.15)
				)
				(justify left bottom)
			)
		)
		(property "Value" "SSM3J332R"
			(at -1.9 2.7 90)
			(layer "F.Fab")
			(effects
				(font
					(size 0.7 0.7)
					(thickness 0.15)
				)
				(justify left bottom)
			)
		)
		(property "Datasheet" "https://www.mouser.com/datasheet/2/408/SSM3J332R_datasheet_en_20181015-1150575.pdf"
			(at 0 0 90)
			(layer "F.Fab")
			(hide yes)
			(effects
				(font
					(size 1.27 1.27)
					(thickness 0.15)
				)
			)
		)
		(property "MPN" "SSM3J332R,LF"
			(at 0 0 90)
			(unlocked yes)
			(layer "F.Fab")
			(hide yes)
			(effects
				(font
					(size 1 1)
					(thickness 0.15)
				)
			)
		)
		(property "Manufacturer" "Toshiba"
			(at 0 0 90)
			(unlocked yes)
			(layer "F.Fab")
			(hide yes)
			(effects
				(font
					(size 1 1)
					(thickness 0.15)
				)
			)
		)
		(property "Author" "Antmicro"
			(at 0 0 90)
			(unlocked yes)
			(layer "F.Fab")
			(hide yes)
			(effects
				(font
					(size 1 1)
					(thickness 0.15)
				)
			)
		)
		(property "License" "Apache-2.0"
			(at 0 0 90)
			(unlocked yes)
			(layer "F.Fab")
			(hide yes)
			(effects
				(font
					(size 1 1)
					(thickness 0.15)
				)
			)
		)
		(sheetname "/USB/")
		(sheetfile "usb.kicad_sch")
		(attr smd)
		(fp_line
			(start 0.7 -1.5)
			(end -0.7 -1.5)
			(stroke
				(width 0.15)
				(type solid)
			)
			(layer "F.SilkS")
		)
		(fp_line
			(start -0.85 -1.35)
			(end -0.7 -1.5)
			(stroke
				(width 0.15)
				(type solid)
			)
			(layer "F.SilkS")
		)
		(fp_line
			(start -1.45 -1.35)
			(end -0.85 -1.35)
			(stroke
				(width 0.15)
				(type solid)
			)
			(layer "F.SilkS")
		)
		(fp_line
			(start 0.7 -0.4)
			(end 0.7 -1.5)
			(stroke
				(width 0.15)
				(type solid)
			)
			(layer "F.SilkS")
		)
		(fp_line
			(start 0.7 0.4)
			(end 0.7 1.5)
			(stroke
				(width 0.15)
				(type solid)
			)
			(layer "F.SilkS")
		)
		(fp_line
			(start 0.7 1.5)
			(end -0.7 1.5)
			(stroke
				(width 0.15)
				(type solid)
			)
			(layer "F.SilkS")
		)
		(fp_line
			(start -0.7 1.5)
			(end -0.7 1.35)
			(stroke
				(width 0.15)
				(type solid)
			)
			(layer "F.SilkS")
		)
		(fp_line
			(start 0.825 -1.6)
			(end 0.825 -0.45)
			(stroke
				(width 0.05)
				(type solid)
			)
			(layer "F.CrtYd")
		)
		(fp_line
			(start -0.9 -1.6)
			(end 0.825 -1.6)
			(stroke
				(width 0.05)
				(type solid)
			)
			(layer "F.CrtYd")
		)
		(fp_line
			(start -0.9 -1.6)
			(end -0.9 -1.4)
			(stroke
				(width 0.05)
				(type solid)
			)
			(layer "F.CrtYd")
		)
		(fp_line
			(start -0.9 -1.4)
			(end -1.75 -1.4)
			(stroke
				(width 0.05)
				(type solid)
			)
			(layer "F.CrtYd")
		)
		(fp_line
			(start -0.85 -0.5)
			(end -1.75 -0.5)
			(stroke
				(width 0.05)
				(type solid)
			)
			(layer "F.CrtYd")
		)
		(fp_line
			(start -1.75 -0.5)
			(end -1.75 -1.4)
			(stroke
				(width 0.05)
				(type solid)
			)
			(layer "F.CrtYd")
		)
		(fp_line
			(start 1.75 -0.45)
			(end 1.75 0.45)
			(stroke
				(width 0.05)
				(type solid)
			)
			(layer "F.CrtYd")
		)
		(fp_line
			(start 0.825 -0.45)
			(end 1.75 -0.45)
			(stroke
				(width 0.05)
				(type solid)
			)
			(layer "F.CrtYd")
		)
		(fp_line
			(start 1.75 0.45)
			(end 0.85 0.45)
			(stroke
				(width 0.05)
				(type solid)
			)
			(layer "F.CrtYd")
		)
		(fp_line
			(start 0.85 0.45)
			(end 0.85 1.65)
			(stroke
				(width 0.05)
				(type solid)
			)
			(layer "F.CrtYd")
		)
		(fp_line
			(start -0.85 0.5)
			(end -0.85 -0.5)
			(stroke
				(width 0.05)
				(type solid)
			)
			(layer "F.CrtYd")
		)
		(fp_line
			(start -1.75 0.5)
			(end -0.85 0.5)
			(stroke
				(width 0.05)
				(type solid)
			)
			(layer "F.CrtYd")
		)
		(fp_line
			(start -0.85 1.4)
			(end -1.75 1.4)
			(stroke
				(width 0.05)
				(type solid)
			)
			(layer "F.CrtYd")
		)
		(fp_line
			(start -1.75 1.4)
			(end -1.75 0.5)
			(stroke
				(width 0.05)
				(type solid)
			)
			(layer "F.CrtYd")
		)
		(fp_line
			(start 0.85 1.65)
			(end -0.85 1.65)
			(stroke
				(width 0.05)
				(type solid)
			)
			(layer "F.CrtYd")
		)
		(fp_line
			(start -0.85 1.65)
			(end -0.85 1.4)
			(stroke
				(width 0.05)
				(type solid)
			)
			(layer "F.CrtYd")
		)
		(fp_line
			(start -0.437 -1.526)
			(end 0.688 -1.526)
			(stroke
				(width 0.15)
				(type solid)
			)
			(layer "F.Fab")
		)
		(fp_line
			(start -0.437 -1.526)
			(end -0.712 -1.325)
			(stroke
				(width 0.15)
				(type solid)
			)
			(layer "F.Fab")
		)
		(fp_line
			(start -0.712 -1.325)
			(end -0.712 1.523)
			(stroke
				(width 0.15)
				(type solid)
			)
			(layer "F.Fab")
		)
		(fp_line
			(start 0.688 1.519)
			(end 0.688 -1.52)
			(stroke
				(width 0.15)
				(type solid)
			)
			(layer "F.Fab")
		)
		(fp_line
			(start -0.712 1.519)
			(end 0.688 1.519)
			(stroke
				(width 0.15)
				(type solid)
			)
			(layer "F.Fab")
		)
		(fp_text user "License: Apache-2.0"
			(at -1.8 6.8 90)
			(layer "F.Fab")
			(effects
				(font
					(size 0.7 0.7)
					(thickness 0.15)
				)
				(justify left bottom)
			)
		)
		(fp_text user "${REFERENCE}"
			(at -1.837 4 90)
			(layer "F.Fab")
			(effects
				(font
					(size 0.7 0.7)
					(thickness 0.15)
				)
				(justify left bottom)
			)
		)
		(fp_text user "Author: Antmicro"
			(at -1.837 5.3 90)
			(layer "F.Fab")
			(effects
				(font
					(size 0.7 0.7)
					(thickness 0.15)
				)
				(justify left bottom)
			)
		)
		(pad "1" smd roundrect
			(at -1.1 -0.951 90)
			(size 1 0.6)
			(layers "F.Cu" "F.Mask" "F.Paste")
			(roundrect_rratio 0.15)
			(net 127 "Net-(Q903-G)")
			(pinfunction "G")
			(pintype "input")
		)
		(pad "2" smd roundrect
			(at -1.1 0.949 90)
			(size 1 0.6)
			(layers "F.Cu" "F.Mask" "F.Paste")
			(roundrect_rratio 0.15)
			(net 10 "+5V")
			(pinfunction "S")
			(pintype "passive")
		)
		(pad "3" smd roundrect
			(at 1.1 -0.0005 90)
			(size 1 0.6)
			(layers "F.Cu" "F.Mask" "F.Paste")
			(roundrect_rratio 0.15)
			(net 28 "/USB/+5V_{CAP}")
			(pinfunction "D")
			(pintype "passive")
		)
	)
)
